(kicad_pcb
	(version 20260206)
	(generator "pcbnew")
	(generator_version "10.0")
	(general
		(thickness 1.6)
		(legacy_teardrops no)
	)
	(paper "A4")
	(title_block
		(title "01162023_DA0F0TEBIF0_F0T_Expander_BD_F_brd_V02_OCP.brd")
		(comment 1 "Grand Teton / footprint 6602 of 9728 (PEX1), pads 957-1074 of 2397")
	)
	(layers
		(0 "F.Cu" signal "TOP")
		(4 "In1.Cu" signal "GND")
		(6 "In2.Cu" signal "VCC")
		(8 "In3.Cu" signal "VCC1")
		(10 "In4.Cu" signal "GND1")
		(12 "In5.Cu" signal "IN1")
		(14 "In6.Cu" signal "GND2")
		(16 "In7.Cu" signal "IN2")
		(18 "In8.Cu" signal "GND3")
		(20 "In9.Cu" signal "IN3")
		(22 "In10.Cu" signal "GND4")
		(24 "In11.Cu" signal "IN4")
		(26 "In12.Cu" signal "GND5")
		(28 "In13.Cu" signal "IN5")
		(30 "In14.Cu" signal "GND6")
		(32 "In15.Cu" signal "IN6")
		(34 "In16.Cu" signal "GND7")
		(2 "B.Cu" signal "BOTTOM")
		(9 "F.Adhes" user "F.Adhesive")
		(11 "B.Adhes" user "B.Adhesive")
		(13 "F.Paste" user "Package Geometry/Pastemask Top")
		(15 "B.Paste" user "Package Geometry/Pastemask Bottom")
		(5 "F.SilkS" user "Ref Des/Silkscreen Top")
		(7 "B.SilkS" user "Ref Des/Silkscreen Bottom")
		(1 "F.Mask" user "Board Geometry/Soldermask Top")
		(3 "B.Mask" user "Board Geometry/Soldermask Bottom")
		(17 "Dwgs.User" user "User.Drawings")
		(19 "Cmts.User" user "User.Comments")
		(21 "Eco1.User" user "User.Eco1")
		(23 "Eco2.User" user "User.Eco2")
		(25 "Edge.Cuts" user "Board Geometry/Outline")
		(27 "Margin" user)
		(31 "F.CrtYd" user "Package Geometry/Place Bound Top")
		(29 "B.CrtYd" user "Package Geometry/Place Bound Bottom")
		(35 "F.Fab" user "Ref Des/Assembly Top")
		(33 "B.Fab" user "Ref Des/Assembly Bottom")
	)
	(footprint ""
		(layer "F.Cu")
		(at 175.749966 -295.89984)
		(property "Reference" "PEX1"
			(at -3.353562 35.593274 0)
			(unlocked yes)
			(layer "F.SilkS")
			(effects
				(font
					(size 2.032 1.524)
					(thickness 0.1524)
				)
				(justify left)
			)
		)
		(property "Value" ""
			(at 0 0 0)
			(layer "F.Fab")
			(effects
				(font
					(size 1.27 1.27)
				)
			)
		)
		(duplicate_pad_numbers_are_jumpers no)
		(pad "AW28" smd circle
			(at 2.84988 13.299948)
			(size 0.4572 0.4572)
			(layers "F.Cu" "F.Mask" "F.Paste")
			(net "PEX1_MODE_SEL4")
		)
		(pad "AW29" smd circle
			(at 3.800094 13.299948)
			(size 0.4572 0.4572)
			(layers "F.Cu" "F.Mask" "F.Paste")
			(net "PEX1_MODE_SEL8")
		)
		(pad "AW30" smd circle
			(at 4.750054 13.299948)
			(size 0.4572 0.4572)
			(layers "F.Cu" "F.Mask" "F.Paste")
			(net "PEX1_DBG_MODE2")
		)
		(pad "AW31" smd circle
			(at 5.700014 13.299948)
			(size 0.4572 0.4572)
			(layers "F.Cu" "F.Mask" "F.Paste")
			(net "PEX1_MODE_SEL11")
		)
		(pad "AW32" smd circle
			(at 6.649974 13.299948)
			(size 0.4572 0.4572)
			(layers "F.Cu" "F.Mask" "F.Paste")
			(net "PEX1_MODE_SEL12")
		)
		(pad "AW33" smd circle
			(at 7.599934 13.299948)
			(size 0.4572 0.4572)
			(layers "F.Cu" "F.Mask" "F.Paste")
			(net "Net_5260")
		)
		(pad "AW34" smd circle
			(at 8.549894 13.299948)
			(size 0.4572 0.4572)
			(layers "F.Cu" "F.Mask" "F.Paste")
			(net "PEX1_DBG_MODE4")
		)
		(pad "AW35" smd circle
			(at 9.500108 13.299948)
			(size 0.4572 0.4572)
			(layers "F.Cu" "F.Mask" "F.Paste")
			(net "Net_5239")
		)
		(pad "AW36" smd circle
			(at 10.450068 13.299948)
			(size 0.4572 0.4572)
			(layers "F.Cu" "F.Mask" "F.Paste")
			(net "Net_5263")
		)
		(pad "AW37" smd circle
			(at 11.400028 13.299948)
			(size 0.4572 0.4572)
			(layers "F.Cu" "F.Mask" "F.Paste")
			(net "Net_5267")
		)
		(pad "AW38" smd circle
			(at 12.349988 13.299948)
			(size 0.4572 0.4572)
			(layers "F.Cu" "F.Mask" "F.Paste")
			(net "PEX1_MODE_SEL1")
		)
		(pad "AW39" smd circle
			(at 13.299948 13.299948)
			(size 0.4572 0.4572)
			(layers "F.Cu" "F.Mask" "F.Paste")
			(net "Net_5234")
		)
		(pad "AW40" smd circle
			(at 14.249908 13.299948)
			(size 0.4572 0.4572)
			(layers "F.Cu" "F.Mask" "F.Paste")
			(net "GND")
		)
		(pad "AW41" smd circle
			(at 15.200122 13.299948)
			(size 0.4572 0.4572)
			(layers "F.Cu" "F.Mask" "F.Paste")
			(net "GND")
		)
		(pad "AW42" smd circle
			(at 16.150082 13.299948)
			(size 0.4572 0.4572)
			(layers "F.Cu" "F.Mask" "F.Paste")
			(net "GND")
		)
		(pad "AW43" smd circle
			(at 17.100042 13.299948)
			(size 0.4572 0.4572)
			(layers "F.Cu" "F.Mask" "F.Paste")
			(net "P5E_PEX1_STN0_TX_DP<6>")
		)
		(pad "AW44" smd circle
			(at 18.050002 13.299948)
			(size 0.4572 0.4572)
			(layers "F.Cu" "F.Mask" "F.Paste")
			(net "P5E_PEX1_STN0_TX_DN<6>")
		)
		(pad "AW45" smd circle
			(at 18.999962 13.299948)
			(size 0.4572 0.4572)
			(layers "F.Cu" "F.Mask" "F.Paste")
			(net "GND")
		)
		(pad "AW46" smd circle
			(at 19.949922 13.299948)
			(size 0.4572 0.4572)
			(layers "F.Cu" "F.Mask" "F.Paste")
			(net "P5E_PEX1_STN0_RX_DP<6>")
		)
		(pad "AW47" smd circle
			(at 20.899882 13.299948)
			(size 0.4572 0.4572)
			(layers "F.Cu" "F.Mask" "F.Paste")
			(net "P5E_PEX1_STN0_RX_DN<6>")
		)
		(pad "AW48" smd circle
			(at 21.850096 13.299948)
			(size 0.4572 0.4572)
			(layers "F.Cu" "F.Mask" "F.Paste")
			(net "GND")
		)
		(pad "AW49" smd circle
			(at 22.800056 13.299948)
			(size 0.4572 0.4572)
			(layers "F.Cu" "F.Mask" "F.Paste")
			(net "GND")
		)
		(pad "AY1" smd circle
			(at -22.800056 14.249908)
			(size 0.4572 0.4572)
			(layers "F.Cu" "F.Mask" "F.Paste")
			(net "Net_1426")
		)
		(pad "AY2" smd circle
			(at -21.850096 14.249908)
			(size 0.4572 0.4572)
			(layers "F.Cu" "F.Mask" "F.Paste")
			(net "Net_1389")
		)
		(pad "AY3" smd circle
			(at -20.899882 14.249908)
			(size 0.4572 0.4572)
			(layers "F.Cu" "F.Mask" "F.Paste")
			(net "GND")
		)
		(pad "AY4" smd circle
			(at -19.949922 14.249908)
			(size 0.4572 0.4572)
			(layers "F.Cu" "F.Mask" "F.Paste")
			(net "GND")
		)
		(pad "AY5" smd circle
			(at -18.999962 14.249908)
			(size 0.4572 0.4572)
			(layers "F.Cu" "F.Mask" "F.Paste")
			(net "GND")
		)
		(pad "AY6" smd circle
			(at -18.050002 14.249908)
			(size 0.4572 0.4572)
			(layers "F.Cu" "F.Mask" "F.Paste")
			(net "GND")
		)
		(pad "AY7" smd circle
			(at -17.100042 14.249908)
			(size 0.4572 0.4572)
			(layers "F.Cu" "F.Mask" "F.Paste")
			(net "GND")
		)
		(pad "AY8" smd circle
			(at -16.150082 14.249908)
			(size 0.4572 0.4572)
			(layers "F.Cu" "F.Mask" "F.Paste")
			(net "GND")
		)
		(pad "AY9" smd circle
			(at -15.200122 14.249908)
			(size 0.4572 0.4572)
			(layers "F.Cu" "F.Mask" "F.Paste")
			(net "GND")
		)
		(pad "AY10" smd circle
			(at -14.249908 14.249908)
			(size 0.4572 0.4572)
			(layers "F.Cu" "F.Mask" "F.Paste")
			(net "GND")
		)
		(pad "AY11" smd circle
			(at -13.299948 14.249908)
			(size 0.4572 0.4572)
			(layers "F.Cu" "F.Mask" "F.Paste")
			(net "GND")
		)
		(pad "AY12" smd circle
			(at -12.349988 14.249908)
			(size 0.4572 0.4572)
			(layers "F.Cu" "F.Mask" "F.Paste")
			(net "GND")
		)
		(pad "AY13" smd circle
			(at -11.400028 14.249908)
			(size 0.4572 0.4572)
			(layers "F.Cu" "F.Mask" "F.Paste")
			(net "GND")
		)
		(pad "AY14" smd circle
			(at -10.450068 14.249908)
			(size 0.4572 0.4572)
			(layers "F.Cu" "F.Mask" "F.Paste")
			(net "GND")
		)
		(pad "AY15" smd circle
			(at -9.500108 14.249908)
			(size 0.4572 0.4572)
			(layers "F.Cu" "F.Mask" "F.Paste")
			(net "GND")
		)
		(pad "AY16" smd circle
			(at -8.549894 14.249908)
			(size 0.4572 0.4572)
			(layers "F.Cu" "F.Mask" "F.Paste")
			(net "GND")
		)
		(pad "AY17" smd circle
			(at -7.599934 14.249908)
			(size 0.4572 0.4572)
			(layers "F.Cu" "F.Mask" "F.Paste")
			(net "GND")
		)
		(pad "AY18" smd circle
			(at -6.649974 14.249908)
			(size 0.4572 0.4572)
			(layers "F.Cu" "F.Mask" "F.Paste")
			(net "GND")
		)
		(pad "AY19" smd circle
			(at -5.700014 14.249908)
			(size 0.4572 0.4572)
			(layers "F.Cu" "F.Mask" "F.Paste")
			(net "GND")
		)
		(pad "AY20" smd circle
			(at -4.750054 14.249908)
			(size 0.4572 0.4572)
			(layers "F.Cu" "F.Mask" "F.Paste")
			(net "GND")
		)
		(pad "AY21" smd circle
			(at -3.800094 14.249908)
			(size 0.4572 0.4572)
			(layers "F.Cu" "F.Mask" "F.Paste")
			(net "GND")
		)
		(pad "AY22" smd circle
			(at -2.84988 14.249908)
			(size 0.4572 0.4572)
			(layers "F.Cu" "F.Mask" "F.Paste")
			(net "GND")
		)
		(pad "AY23" smd circle
			(at -1.89992 14.249908)
			(size 0.4572 0.4572)
			(layers "F.Cu" "F.Mask" "F.Paste")
			(net "GND")
		)
		(pad "AY24" smd circle
			(at -0.94996 14.249908)
			(size 0.4572 0.4572)
			(layers "F.Cu" "F.Mask" "F.Paste")
			(net "GND")
		)
		(pad "AY25" smd circle
			(at 0 14.249908)
			(size 0.4572 0.4572)
			(layers "F.Cu" "F.Mask" "F.Paste")
			(net "GND")
		)
		(pad "AY26" smd circle
			(at 0.94996 14.249908)
			(size 0.4572 0.4572)
			(layers "F.Cu" "F.Mask" "F.Paste")
			(net "GND")
		)
		(pad "AY27" smd circle
			(at 1.89992 14.249908)
			(size 0.4572 0.4572)
			(layers "F.Cu" "F.Mask" "F.Paste")
			(net "GND")
		)
		(pad "AY28" smd circle
			(at 2.84988 14.249908)
			(size 0.4572 0.4572)
			(layers "F.Cu" "F.Mask" "F.Paste")
			(net "GND")
		)
		(pad "AY29" smd circle
			(at 3.800094 14.249908)
			(size 0.4572 0.4572)
			(layers "F.Cu" "F.Mask" "F.Paste")
			(net "GND")
		)
		(pad "AY30" smd circle
			(at 4.750054 14.249908)
			(size 0.4572 0.4572)
			(layers "F.Cu" "F.Mask" "F.Paste")
			(net "GND")
		)
		(pad "AY31" smd circle
			(at 5.700014 14.249908)
			(size 0.4572 0.4572)
			(layers "F.Cu" "F.Mask" "F.Paste")
			(net "GND")
		)
		(pad "AY32" smd circle
			(at 6.649974 14.249908)
			(size 0.4572 0.4572)
			(layers "F.Cu" "F.Mask" "F.Paste")
			(net "GND")
		)
		(pad "AY33" smd circle
			(at 7.599934 14.249908)
			(size 0.4572 0.4572)
			(layers "F.Cu" "F.Mask" "F.Paste")
			(net "GND")
		)
		(pad "AY34" smd circle
			(at 8.549894 14.249908)
			(size 0.4572 0.4572)
			(layers "F.Cu" "F.Mask" "F.Paste")
			(net "GND")
		)
		(pad "AY35" smd circle
			(at 9.500108 14.249908)
			(size 0.4572 0.4572)
			(layers "F.Cu" "F.Mask" "F.Paste")
			(net "GND")
		)
		(pad "AY36" smd circle
			(at 10.450068 14.249908)
			(size 0.4572 0.4572)
			(layers "F.Cu" "F.Mask" "F.Paste")
			(net "GND")
		)
		(pad "AY37" smd circle
			(at 11.400028 14.249908)
			(size 0.4572 0.4572)
			(layers "F.Cu" "F.Mask" "F.Paste")
			(net "GND")
		)
		(pad "AY38" smd circle
			(at 12.349988 14.249908)
			(size 0.4572 0.4572)
			(layers "F.Cu" "F.Mask" "F.Paste")
			(net "GND")
		)
		(pad "AY39" smd circle
			(at 13.299948 14.249908)
			(size 0.4572 0.4572)
			(layers "F.Cu" "F.Mask" "F.Paste")
			(net "GND")
		)
		(pad "AY40" smd circle
			(at 14.249908 14.249908)
			(size 0.4572 0.4572)
			(layers "F.Cu" "F.Mask" "F.Paste")
			(net "GND")
		)
		(pad "AY41" smd circle
			(at 15.200122 14.249908)
			(size 0.4572 0.4572)
			(layers "F.Cu" "F.Mask" "F.Paste")
			(net "GND")
		)
		(pad "AY42" smd circle
			(at 16.150082 14.249908)
			(size 0.4572 0.4572)
			(layers "F.Cu" "F.Mask" "F.Paste")
			(net "GND")
		)
		(pad "AY43" smd circle
			(at 17.100042 14.249908)
			(size 0.4572 0.4572)
			(layers "F.Cu" "F.Mask" "F.Paste")
			(net "GND")
		)
		(pad "AY44" smd circle
			(at 18.050002 14.249908)
			(size 0.4572 0.4572)
			(layers "F.Cu" "F.Mask" "F.Paste")
			(net "GND")
		)
		(pad "AY45" smd circle
			(at 18.999962 14.249908)
			(size 0.4572 0.4572)
			(layers "F.Cu" "F.Mask" "F.Paste")
			(net "GND")
		)
		(pad "AY46" smd circle
			(at 19.949922 14.249908)
			(size 0.4572 0.4572)
			(layers "F.Cu" "F.Mask" "F.Paste")
			(net "GND")
		)
		(pad "AY47" smd circle
			(at 20.899882 14.249908)
			(size 0.4572 0.4572)
			(layers "F.Cu" "F.Mask" "F.Paste")
			(net "GND")
		)
		(pad "AY48" smd circle
			(at 21.850096 14.249908)
			(size 0.4572 0.4572)
			(layers "F.Cu" "F.Mask" "F.Paste")
			(net "P5E_PEX1_STN0_RX_DP<7>")
		)
		(pad "AY49" smd circle
			(at 22.800056 14.249908)
			(size 0.4572 0.4572)
			(layers "F.Cu" "F.Mask" "F.Paste")
			(net "P5E_PEX1_STN0_RX_DN<7>")
		)
		(pad "B1" smd circle
			(at -22.800056 -21.850096)
			(size 0.4572 0.4572)
			(layers "F.Cu" "F.Mask" "F.Paste")
			(net "GND")
		)
		(pad "B2" smd circle
			(at -21.850096 -21.850096)
			(size 0.4572 0.4572)
			(layers "F.Cu" "F.Mask" "F.Paste")
			(net "GND")
		)
		(pad "B3" smd circle
			(at -20.899882 -21.850096)
			(size 0.4572 0.4572)
			(layers "F.Cu" "F.Mask" "F.Paste")
			(net "P5E_PEX1_STN7_RX_DP<123>")
		)
		(pad "B4" smd circle
			(at -19.949922 -21.850096)
			(size 0.4572 0.4572)
			(layers "F.Cu" "F.Mask" "F.Paste")
			(net "GND")
		)
		(pad "B5" smd circle
			(at -18.999962 -21.850096)
			(size 0.4572 0.4572)
			(layers "F.Cu" "F.Mask" "F.Paste")
			(net "P5E_PEX1_STN7_RX_DP<125>")
		)
		(pad "B6" smd circle
			(at -18.050002 -21.850096)
			(size 0.4572 0.4572)
			(layers "F.Cu" "F.Mask" "F.Paste")
			(net "GND")
		)
		(pad "B7" smd circle
			(at -17.100042 -21.850096)
			(size 0.4572 0.4572)
			(layers "F.Cu" "F.Mask" "F.Paste")
			(net "P5E_PEX1_STN7_RX_DP<127>")
		)
		(pad "B8" smd circle
			(at -16.150082 -21.850096)
			(size 0.4572 0.4572)
			(layers "F.Cu" "F.Mask" "F.Paste")
			(net "GND")
		)
		(pad "B9" smd circle
			(at -15.200122 -21.850096)
			(size 0.4572 0.4572)
			(layers "F.Cu" "F.Mask" "F.Paste")
			(net "P5E_PEX1_STN6_RX_DP<110>")
		)
		(pad "B10" smd circle
			(at -14.249908 -21.850096)
			(size 0.4572 0.4572)
			(layers "F.Cu" "F.Mask" "F.Paste")
			(net "GND")
		)
		(pad "B11" smd circle
			(at -13.299948 -21.850096)
			(size 0.4572 0.4572)
			(layers "F.Cu" "F.Mask" "F.Paste")
			(net "P5E_PEX1_STN6_RX_DP<108>")
		)
		(pad "B12" smd circle
			(at -12.349988 -21.850096)
			(size 0.4572 0.4572)
			(layers "F.Cu" "F.Mask" "F.Paste")
			(net "GND")
		)
		(pad "B13" smd circle
			(at -11.400028 -21.850096)
			(size 0.4572 0.4572)
			(layers "F.Cu" "F.Mask" "F.Paste")
			(net "P5E_PEX1_STN6_RX_DP<106>")
		)
		(pad "B14" smd circle
			(at -10.450068 -21.850096)
			(size 0.4572 0.4572)
			(layers "F.Cu" "F.Mask" "F.Paste")
			(net "GND")
		)
		(pad "B15" smd circle
			(at -9.500108 -21.850096)
			(size 0.4572 0.4572)
			(layers "F.Cu" "F.Mask" "F.Paste")
			(net "P5E_PEX1_STN6_RX_DP<104>")
		)
		(pad "B16" smd circle
			(at -8.549894 -21.850096)
			(size 0.4572 0.4572)
			(layers "F.Cu" "F.Mask" "F.Paste")
			(net "GND")
		)
		(pad "B17" smd circle
			(at -7.599934 -21.850096)
			(size 0.4572 0.4572)
			(layers "F.Cu" "F.Mask" "F.Paste")
			(net "P5E_PEX1_STN6_RX_DP<102>")
		)
		(pad "B18" smd circle
			(at -6.649974 -21.850096)
			(size 0.4572 0.4572)
			(layers "F.Cu" "F.Mask" "F.Paste")
			(net "GND")
		)
		(pad "B19" smd circle
			(at -5.700014 -21.850096)
			(size 0.4572 0.4572)
			(layers "F.Cu" "F.Mask" "F.Paste")
			(net "P5E_PEX1_STN6_RX_DP<100>")
		)
		(pad "B20" smd circle
			(at -4.750054 -21.850096)
			(size 0.4572 0.4572)
			(layers "F.Cu" "F.Mask" "F.Paste")
			(net "GND")
		)
		(pad "B21" smd circle
			(at -3.800094 -21.850096)
			(size 0.4572 0.4572)
			(layers "F.Cu" "F.Mask" "F.Paste")
			(net "P5E_PEX1_STN6_RX_DP<98>")
		)
		(pad "B22" smd circle
			(at -2.84988 -21.850096)
			(size 0.4572 0.4572)
			(layers "F.Cu" "F.Mask" "F.Paste")
			(net "GND")
		)
		(pad "B23" smd circle
			(at -1.89992 -21.850096)
			(size 0.4572 0.4572)
			(layers "F.Cu" "F.Mask" "F.Paste")
			(net "P5E_PEX1_STN6_RX_DP<96>")
		)
		(pad "B24" smd circle
			(at -0.94996 -21.850096)
			(size 0.4572 0.4572)
			(layers "F.Cu" "F.Mask" "F.Paste")
			(net "GND")
		)
		(pad "B25" smd circle
			(at 0 -21.850096)
			(size 0.4572 0.4572)
			(layers "F.Cu" "F.Mask" "F.Paste")
			(net "P5E_PEX1_STN5_RX_DP<81>")
		)
		(pad "B26" smd circle
			(at 0.94996 -21.850096)
			(size 0.4572 0.4572)
			(layers "F.Cu" "F.Mask" "F.Paste")
			(net "GND")
		)
		(pad "B27" smd circle
			(at 1.89992 -21.850096)
			(size 0.4572 0.4572)
			(layers "F.Cu" "F.Mask" "F.Paste")
			(net "P5E_PEX1_STN5_RX_DP<83>")
		)
		(pad "B28" smd circle
			(at 2.84988 -21.850096)
			(size 0.4572 0.4572)
			(layers "F.Cu" "F.Mask" "F.Paste")
			(net "GND")
		)
		(pad "B29" smd circle
			(at 3.800094 -21.850096)
			(size 0.4572 0.4572)
			(layers "F.Cu" "F.Mask" "F.Paste")
			(net "P5E_PEX1_STN5_RX_DP<85>")
		)
		(pad "B30" smd circle
			(at 4.750054 -21.850096)
			(size 0.4572 0.4572)
			(layers "F.Cu" "F.Mask" "F.Paste")
			(net "GND")
		)
		(pad "B31" smd circle
			(at 5.700014 -21.850096)
			(size 0.4572 0.4572)
			(layers "F.Cu" "F.Mask" "F.Paste")
			(net "P5E_PEX1_STN5_RX_DP<87>")
		)
		(pad "B32" smd circle
			(at 6.649974 -21.850096)
			(size 0.4572 0.4572)
			(layers "F.Cu" "F.Mask" "F.Paste")
			(net "GND")
		)
		(pad "B33" smd circle
			(at 7.599934 -21.850096)
			(size 0.4572 0.4572)
			(layers "F.Cu" "F.Mask" "F.Paste")
			(net "P5E_PEX1_STN5_RX_DP<89>")
		)
		(pad "B34" smd circle
			(at 8.549894 -21.850096)
			(size 0.4572 0.4572)
			(layers "F.Cu" "F.Mask" "F.Paste")
			(net "GND")
		)
		(pad "B35" smd circle
			(at 9.500108 -21.850096)
			(size 0.4572 0.4572)
			(layers "F.Cu" "F.Mask" "F.Paste")
			(net "P5E_PEX1_STN5_RX_DP<91>")
		)
		(pad "B36" smd circle
			(at 10.450068 -21.850096)
			(size 0.4572 0.4572)
			(layers "F.Cu" "F.Mask" "F.Paste")
			(net "GND")
		)
		(pad "B37" smd circle
			(at 11.400028 -21.850096)
			(size 0.4572 0.4572)
			(layers "F.Cu" "F.Mask" "F.Paste")
			(net "P5E_PEX1_STN5_RX_DP<93>")
		)
		(pad "B38" smd circle
			(at 12.349988 -21.850096)
			(size 0.4572 0.4572)
			(layers "F.Cu" "F.Mask" "F.Paste")
			(net "GND")
		)
		(pad "B39" smd circle
			(at 13.299948 -21.850096)
			(size 0.4572 0.4572)
			(layers "F.Cu" "F.Mask" "F.Paste")
			(net "P5E_PEX1_STN5_RX_DP<95>")
		)
		(pad "B40" smd circle
			(at 14.249908 -21.850096)
			(size 0.4572 0.4572)
			(layers "F.Cu" "F.Mask" "F.Paste")
			(net "GND")
		)
		(pad "B41" smd circle
			(at 15.200122 -21.850096)
			(size 0.4572 0.4572)
			(layers "F.Cu" "F.Mask" "F.Paste")
			(net "P5E_PEX1_STN4_RX_DP<78>")
		)
		(pad "B42" smd circle
			(at 16.150082 -21.850096)
			(size 0.4572 0.4572)
			(layers "F.Cu" "F.Mask" "F.Paste")
			(net "GND")
		)
		(pad "B43" smd circle
			(at 17.100042 -21.850096)
			(size 0.4572 0.4572)
			(layers "F.Cu" "F.Mask" "F.Paste")
			(net "P5E_PEX1_STN4_RX_DP<76>")
		)
		(pad "B44" smd circle
			(at 18.050002 -21.850096)
			(size 0.4572 0.4572)
			(layers "F.Cu" "F.Mask" "F.Paste")
			(net "GND")
		)
		(pad "B45" smd circle
			(at 18.999962 -21.850096)
			(size 0.4572 0.4572)
			(layers "F.Cu" "F.Mask" "F.Paste")
			(net "P5E_PEX1_STN4_RX_DP<74>")
		)
		(pad "B46" smd circle
			(at 19.949922 -21.850096)
			(size 0.4572 0.4572)
			(layers "F.Cu" "F.Mask" "F.Paste")
			(net "GND")
		)
		(pad "B47" smd circle
			(at 20.899882 -21.850096)
			(size 0.4572 0.4572)
			(layers "F.Cu" "F.Mask" "F.Paste")
			(net "P5E_PEX1_STN4_RX_DP<72>")
		)
	)
)
